# T6G (Grand Teton) — schematic netlist excerpt (pin names and nets, part order shuffled) for the footprints in the layout excerpt that follows; sources: Cadence DE-HDL packaged netlist, KiCad conversion of 04192023_DAF0TMB3IC0_F0TG_MB_C_brd_V02_OCP.brd

C5002  Q_CAP  1000PF 50V 5% X7R  pkg 0402  page 192 : A = FM_PWRGD_PVDD33_S5 ; B = GND
R936  Q_RES  0 5% CHIP  pkg 0402LF  page 166 : A = FM_SMERR_BUF_LED_N ; B = FM_SMERR_BUF_R_LED_N

(kicad_pcb
	(version 20260206)
	(generator "pcbnew")
	(generator_version "10.0")
	(general
		(thickness 1.6)
		(legacy_teardrops no)
	)
	(paper "A4")
	(title_block
		(title "04192023_DAF0TMB3IC0_F0TG_MB_C_brd_V02_OCP.brd")
		(comment 1 "Grand Teton / footprints 1550-1551 of 8354")
	)
	(layers
		(0 "F.Cu" signal "TOP")
		(4 "In1.Cu" signal "GND")
		(6 "In2.Cu" signal "IN1")
		(8 "In3.Cu" signal "GND1")
		(10 "In4.Cu" signal "IN2")
		(12 "In5.Cu" signal "GND2")
		(14 "In6.Cu" signal "IN3")
		(16 "In7.Cu" signal "GND3")
		(18 "In8.Cu" signal "VCC")
		(20 "In9.Cu" signal "VCC1")
		(22 "In10.Cu" signal "GND4")
		(24 "In11.Cu" signal "IN4")
		(26 "In12.Cu" signal "GND5")
		(28 "In13.Cu" signal "IN5")
		(30 "In14.Cu" signal "GND6")
		(32 "In15.Cu" signal "IN6")
		(34 "In16.Cu" signal "GND7")
		(2 "B.Cu" signal "BOTTOM")
		(9 "F.Adhes" user "F.Adhesive")
		(11 "B.Adhes" user "B.Adhesive")
		(13 "F.Paste" user "Package Geometry/Pastemask Top")
		(15 "B.Paste" user "Package Geometry/Pastemask Bottom")
		(5 "F.SilkS" user "Ref Des/Silkscreen Top")
		(7 "B.SilkS" user "Ref Des/Silkscreen Bottom")
		(1 "F.Mask" user "Board Geometry/Soldermask Top")
		(3 "B.Mask" user "Board Geometry/Soldermask Bottom")
		(17 "Dwgs.User" user "User.Drawings")
		(19 "Cmts.User" user "User.Comments")
		(21 "Eco1.User" user "User.Eco1")
		(23 "Eco2.User" user "User.Eco2")
		(25 "Edge.Cuts" user "Board Geometry/Outline")
		(27 "Margin" user)
		(31 "F.CrtYd" user "Package Geometry/Place Bound Top")
		(29 "B.CrtYd" user "Package Geometry/Place Bound Bottom")
		(35 "F.Fab" user "Ref Des/Assembly Top")
		(33 "B.Fab" user "Ref Des/Assembly Bottom")
	)
	(footprint ""
		(layer "F.Cu")
		(at 197.273926 -106.543856)
		(property "Reference" "C5002"
			(at 0 0 0)
			(layer "F.SilkS")
			(hide yes)
			(effects
				(font
					(size 1.27 1.27)
				)
			)
		)
		(property "Value" ""
			(at 0 0 0)
			(layer "F.Fab")
			(effects
				(font
					(size 1.27 1.27)
				)
			)
		)
		(duplicate_pad_numbers_are_jumpers no)
		(fp_line
			(start -0.7874 -0.4064)
			(end 0.7874 -0.4064)
			(stroke
				(width 0.1524)
				(type default)
			)
			(layer "F.SilkS")
		)
		(fp_line
			(start -0.7874 0.4064)
			(end -0.7874 -0.4064)
			(stroke
				(width 0.1524)
				(type default)
			)
			(layer "F.SilkS")
		)
		(fp_line
			(start 0.7874 -0.4064)
			(end 0.7874 0.4064)
			(stroke
				(width 0.1524)
				(type default)
			)
			(layer "F.SilkS")
		)
		(fp_line
			(start 0.7874 0.4064)
			(end -0.7874 0.4064)
			(stroke
				(width 0.1524)
				(type default)
			)
			(layer "F.SilkS")
		)
		(fp_line
			(start -0.67945 -0.305054)
			(end -0.12065 -0.305054)
			(stroke
				(width 0.1)
				(type default)
			)
			(layer "F.Fab")
		)
		(fp_line
			(start -0.67945 0.3048)
			(end -0.67945 -0.305054)
			(stroke
				(width 0.1)
				(type default)
			)
			(layer "F.Fab")
		)
		(fp_line
			(start -0.12065 -0.305054)
			(end -0.12065 -0.2794)
			(stroke
				(width 0.1)
				(type default)
			)
			(layer "F.Fab")
		)
		(fp_line
			(start -0.12065 -0.2794)
			(end 0.12065 -0.2794)
			(stroke
				(width 0.1)
				(type default)
			)
			(layer "F.Fab")
		)
		(fp_line
			(start -0.12065 0.2794)
			(end -0.12065 0.3048)
			(stroke
				(width 0.1)
				(type default)
			)
			(layer "F.Fab")
		)
		(fp_line
			(start -0.12065 0.3048)
			(end -0.67945 0.3048)
			(stroke
				(width 0.1)
				(type default)
			)
			(layer "F.Fab")
		)
		(fp_line
			(start 0.120396 0.2794)
			(end -0.12065 0.2794)
			(stroke
				(width 0.1)
				(type default)
			)
			(layer "F.Fab")
		)
		(fp_line
			(start 0.120396 0.3048)
			(end 0.120396 0.2794)
			(stroke
				(width 0.1)
				(type default)
			)
			(layer "F.Fab")
		)
		(fp_line
			(start 0.12065 -0.3048)
			(end 0.67945 -0.3048)
			(stroke
				(width 0.1)
				(type default)
			)
			(layer "F.Fab")
		)
		(fp_line
			(start 0.12065 -0.2794)
			(end 0.12065 -0.3048)
			(stroke
				(width 0.1)
				(type default)
			)
			(layer "F.Fab")
		)
		(fp_line
			(start 0.67945 -0.3048)
			(end 0.67945 0.3048)
			(stroke
				(width 0.1)
				(type default)
			)
			(layer "F.Fab")
		)
		(fp_line
			(start 0.67945 0.3048)
			(end 0.120396 0.3048)
			(stroke
				(width 0.1)
				(type default)
			)
			(layer "F.Fab")
		)
		(pad "1" smd circle
			(at -0.40005 0)
			(size 0 0)
			(layers "F.Cu" "F.Mask" "F.Paste")
			(net "FM_PWRGD_PVDD33_S5")
		)
		(pad "2" smd circle
			(at 0.40005 0)
			(size 0 0)
			(layers "F.Cu" "F.Mask" "F.Paste")
			(net "GND")
		)
	)
	(footprint ""
		(layer "F.Cu")
		(at 344.474546 -23.8887 -90)
		(property "Reference" "R936"
			(at 0 0 270)
			(layer "F.SilkS")
			(hide yes)
			(effects
				(font
					(size 1.27 1.27)
				)
			)
		)
		(property "Value" ""
			(at 0 0 270)
			(layer "F.Fab")
			(effects
				(font
					(size 1.27 1.27)
				)
			)
		)
		(duplicate_pad_numbers_are_jumpers no)
		(fp_line
			(start -0.7874 0.4064)
			(end -0.7874 -0.4064)
			(stroke
				(width 0.1524)
				(type default)
			)
			(layer "F.SilkS")
		)
		(fp_line
			(start 0.7874 0.4064)
			(end -0.7874 0.4064)
			(stroke
				(width 0.1524)
				(type default)
			)
			(layer "F.SilkS")
		)
		(fp_line
			(start -0.7874 -0.4064)
			(end 0.7874 -0.4064)
			(stroke
				(width 0.1524)
				(type default)
			)
			(layer "F.SilkS")
		)
		(fp_line
			(start 0.7874 -0.4064)
			(end 0.7874 0.4064)
			(stroke
				(width 0.1524)
				(type default)
			)
			(layer "F.SilkS")
		)
		(fp_line
			(start -0.67945 0.3048)
			(end -0.67945 -0.305054)
			(stroke
				(width 0.1)
				(type default)
			)
			(layer "F.Fab")
		)
		(fp_line
			(start -0.12065 0.3048)
			(end -0.67945 0.3048)
			(stroke
				(width 0.1)
				(type default)
			)
			(layer "F.Fab")
		)
		(fp_line
			(start 0.120396 0.3048)
			(end 0.120396 0.2794)
			(stroke
				(width 0.1)
				(type default)
			)
			(layer "F.Fab")
		)
		(fp_line
			(start 0.67945 0.3048)
			(end 0.120396 0.3048)
			(stroke
				(width 0.1)
				(type default)
			)
			(layer "F.Fab")
		)
		(fp_line
			(start -0.12065 0.2794)
			(end -0.12065 0.3048)
			(stroke
				(width 0.1)
				(type default)
			)
			(layer "F.Fab")
		)
		(fp_line
			(start 0.120396 0.2794)
			(end -0.12065 0.2794)
			(stroke
				(width 0.1)
				(type default)
			)
			(layer "F.Fab")
		)
		(fp_line
			(start -0.12065 -0.2794)
			(end 0.12065 -0.2794)
			(stroke
				(width 0.1)
				(type default)
			)
			(layer "F.Fab")
		)
		(fp_line
			(start 0.12065 -0.2794)
			(end 0.12065 -0.3048)
			(stroke
				(width 0.1)
				(type default)
			)
			(layer "F.Fab")
		)
		(fp_line
			(start 0.12065 -0.3048)
			(end 0.67945 -0.3048)
			(stroke
				(width 0.1)
				(type default)
			)
			(layer "F.Fab")
		)
		(fp_line
			(start 0.67945 -0.3048)
			(end 0.67945 0.3048)
			(stroke
				(width 0.1)
				(type default)
			)
			(layer "F.Fab")
		)
		(fp_line
			(start -0.67945 -0.305054)
			(end -0.12065 -0.305054)
			(stroke
				(width 0.1)
				(type default)
			)
			(layer "F.Fab")
		)
		(fp_line
			(start -0.12065 -0.305054)
			(end -0.12065 -0.2794)
			(stroke
				(width 0.1)
				(type default)
			)
			(layer "F.Fab")
		)
		(pad "1" smd circle
			(at -0.40005 0 270)
			(size 0 0)
			(layers "F.Cu" "F.Mask" "F.Paste")
			(net "FM_SMERR_BUF_LED_N")
		)
		(pad "2" smd circle
			(at 0.40005 0 270)
			(size 0 0)
			(layers "F.Cu" "F.Mask" "F.Paste")
			(net "FM_SMERR_BUF_R_LED_N")
		)
	)
)
